(kicad_pcb
	(version 20260206)
	(generator "pcbnew")
	(generator_version "10.0")
	(general
		(thickness 1.6)
		(legacy_teardrops no)
	)
	(paper "A4")
	(title_block
		(title "01162023_DA0F0TEBIF0_F0T_Expander_BD_F_brd_V02_OCP.brd")
		(comment 1 "Grand Teton / footprints 3541-3547 of 9728")
	)
	(layers
		(0 "F.Cu" signal "TOP")
		(4 "In1.Cu" signal "GND")
		(6 "In2.Cu" signal "VCC")
		(8 "In3.Cu" signal "VCC1")
		(10 "In4.Cu" signal "GND1")
		(12 "In5.Cu" signal "IN1")
		(14 "In6.Cu" signal "GND2")
		(16 "In7.Cu" signal "IN2")
		(18 "In8.Cu" signal "GND3")
		(20 "In9.Cu" signal "IN3")
		(22 "In10.Cu" signal "GND4")
		(24 "In11.Cu" signal "IN4")
		(26 "In12.Cu" signal "GND5")
		(28 "In13.Cu" signal "IN5")
		(30 "In14.Cu" signal "GND6")
		(32 "In15.Cu" signal "IN6")
		(34 "In16.Cu" signal "GND7")
		(2 "B.Cu" signal "BOTTOM")
		(9 "F.Adhes" user "F.Adhesive")
		(11 "B.Adhes" user "B.Adhesive")
		(13 "F.Paste" user "Package Geometry/Pastemask Top")
		(15 "B.Paste" user "Package Geometry/Pastemask Bottom")
		(5 "F.SilkS" user "Ref Des/Silkscreen Top")
		(7 "B.SilkS" user "Ref Des/Silkscreen Bottom")
		(1 "F.Mask" user "Board Geometry/Soldermask Top")
		(3 "B.Mask" user "Board Geometry/Soldermask Bottom")
		(17 "Dwgs.User" user "User.Drawings")
		(19 "Cmts.User" user "User.Comments")
		(21 "Eco1.User" user "User.Eco1")
		(23 "Eco2.User" user "User.Eco2")
		(25 "Edge.Cuts" user "Board Geometry/Outline")
		(27 "Margin" user)
		(31 "F.CrtYd" user "Package Geometry/Place Bound Top")
		(29 "B.CrtYd" user "Package Geometry/Place Bound Bottom")
		(35 "F.Fab" user "Ref Des/Assembly Top")
		(33 "B.Fab" user "Ref Des/Assembly Bottom")
	)
	(footprint ""
		(layer "F.Cu")
		(at 72.125332 -42.849038 180)
		(property "Reference" "R535"
			(at 0 0 180)
			(layer "F.SilkS")
			(hide yes)
			(effects
				(font
					(size 1.27 1.27)
				)
			)
		)
		(property "Value" ""
			(at 0 0 180)
			(layer "F.Fab")
			(effects
				(font
					(size 1.27 1.27)
				)
			)
		)
		(duplicate_pad_numbers_are_jumpers no)
		(fp_line
			(start 0.7874 0.4064)
			(end -0.7874 0.4064)
			(stroke
				(width 0.1524)
				(type default)
			)
			(layer "F.SilkS")
		)
		(fp_line
			(start 0.7874 -0.4064)
			(end 0.7874 0.4064)
			(stroke
				(width 0.1524)
				(type default)
			)
			(layer "F.SilkS")
		)
		(fp_line
			(start -0.7874 0.4064)
			(end -0.7874 -0.4064)
			(stroke
				(width 0.1524)
				(type default)
			)
			(layer "F.SilkS")
		)
		(fp_line
			(start -0.7874 -0.4064)
			(end 0.7874 -0.4064)
			(stroke
				(width 0.1524)
				(type default)
			)
			(layer "F.SilkS")
		)
		(fp_line
			(start 0.67945 0.3048)
			(end 0.120396 0.3048)
			(stroke
				(width 0.1)
				(type default)
			)
			(layer "F.Fab")
		)
		(fp_line
			(start 0.67945 -0.3048)
			(end 0.67945 0.3048)
			(stroke
				(width 0.1)
				(type default)
			)
			(layer "F.Fab")
		)
		(fp_line
			(start 0.12065 -0.2794)
			(end 0.12065 -0.3048)
			(stroke
				(width 0.1)
				(type default)
			)
			(layer "F.Fab")
		)
		(fp_line
			(start 0.12065 -0.3048)
			(end 0.67945 -0.3048)
			(stroke
				(width 0.1)
				(type default)
			)
			(layer "F.Fab")
		)
		(fp_line
			(start 0.120396 0.3048)
			(end 0.120396 0.2794)
			(stroke
				(width 0.1)
				(type default)
			)
			(layer "F.Fab")
		)
		(fp_line
			(start 0.120396 0.2794)
			(end -0.12065 0.2794)
			(stroke
				(width 0.1)
				(type default)
			)
			(layer "F.Fab")
		)
		(fp_line
			(start -0.12065 0.3048)
			(end -0.67945 0.3048)
			(stroke
				(width 0.1)
				(type default)
			)
			(layer "F.Fab")
		)
		(fp_line
			(start -0.12065 0.2794)
			(end -0.12065 0.3048)
			(stroke
				(width 0.1)
				(type default)
			)
			(layer "F.Fab")
		)
		(fp_line
			(start -0.12065 -0.2794)
			(end 0.12065 -0.2794)
			(stroke
				(width 0.1)
				(type default)
			)
			(layer "F.Fab")
		)
		(fp_line
			(start -0.12065 -0.305054)
			(end -0.12065 -0.2794)
			(stroke
				(width 0.1)
				(type default)
			)
			(layer "F.Fab")
		)
		(fp_line
			(start -0.67945 0.3048)
			(end -0.67945 -0.305054)
			(stroke
				(width 0.1)
				(type default)
			)
			(layer "F.Fab")
		)
		(fp_line
			(start -0.67945 -0.305054)
			(end -0.12065 -0.305054)
			(stroke
				(width 0.1)
				(type default)
			)
			(layer "F.Fab")
		)
		(pad "1" smd circle
			(at -0.40005 0 180)
			(size 0 0)
			(layers "F.Cu" "F.Mask" "F.Paste")
			(net "P12V_SSD2_R")
		)
		(pad "2" smd circle
			(at 0.40005 0 180)
			(size 0 0)
			(layers "F.Cu" "F.Mask" "F.Paste")
			(net "P12V_SSD2_VIN_P")
		)
	)
	(footprint ""
		(layer "F.Cu")
		(at 128.513332 -268.352524 -90)
		(property "Reference" "PC983"
			(at 0 0 270)
			(layer "F.SilkS")
			(hide yes)
			(effects
				(font
					(size 1.27 1.27)
				)
			)
		)
		(property "Value" ""
			(at 0 0 270)
			(layer "F.Fab")
			(effects
				(font
					(size 1.27 1.27)
				)
			)
		)
		(duplicate_pad_numbers_are_jumpers no)
		(fp_line
			(start -0.7874 0.4064)
			(end -0.7874 -0.4064)
			(stroke
				(width 0.1524)
				(type default)
			)
			(layer "F.SilkS")
		)
		(fp_line
			(start 0.7874 0.4064)
			(end -0.7874 0.4064)
			(stroke
				(width 0.1524)
				(type default)
			)
			(layer "F.SilkS")
		)
		(fp_line
			(start -0.7874 -0.4064)
			(end 0.7874 -0.4064)
			(stroke
				(width 0.1524)
				(type default)
			)
			(layer "F.SilkS")
		)
		(fp_line
			(start 0.7874 -0.4064)
			(end 0.7874 0.4064)
			(stroke
				(width 0.1524)
				(type default)
			)
			(layer "F.SilkS")
		)
		(fp_line
			(start -0.67945 0.3048)
			(end -0.67945 -0.305054)
			(stroke
				(width 0.1)
				(type default)
			)
			(layer "F.Fab")
		)
		(fp_line
			(start -0.12065 0.3048)
			(end -0.67945 0.3048)
			(stroke
				(width 0.1)
				(type default)
			)
			(layer "F.Fab")
		)
		(fp_line
			(start 0.120396 0.3048)
			(end 0.120396 0.2794)
			(stroke
				(width 0.1)
				(type default)
			)
			(layer "F.Fab")
		)
		(fp_line
			(start 0.67945 0.3048)
			(end 0.120396 0.3048)
			(stroke
				(width 0.1)
				(type default)
			)
			(layer "F.Fab")
		)
		(fp_line
			(start -0.12065 0.2794)
			(end -0.12065 0.3048)
			(stroke
				(width 0.1)
				(type default)
			)
			(layer "F.Fab")
		)
		(fp_line
			(start 0.120396 0.2794)
			(end -0.12065 0.2794)
			(stroke
				(width 0.1)
				(type default)
			)
			(layer "F.Fab")
		)
		(fp_line
			(start -0.12065 -0.2794)
			(end 0.12065 -0.2794)
			(stroke
				(width 0.1)
				(type default)
			)
			(layer "F.Fab")
		)
		(fp_line
			(start 0.12065 -0.2794)
			(end 0.12065 -0.3048)
			(stroke
				(width 0.1)
				(type default)
			)
			(layer "F.Fab")
		)
		(fp_line
			(start 0.12065 -0.3048)
			(end 0.67945 -0.3048)
			(stroke
				(width 0.1)
				(type default)
			)
			(layer "F.Fab")
		)
		(fp_line
			(start 0.67945 -0.3048)
			(end 0.67945 0.3048)
			(stroke
				(width 0.1)
				(type default)
			)
			(layer "F.Fab")
		)
		(fp_line
			(start -0.67945 -0.305054)
			(end -0.12065 -0.305054)
			(stroke
				(width 0.1)
				(type default)
			)
			(layer "F.Fab")
		)
		(fp_line
			(start -0.12065 -0.305054)
			(end -0.12065 -0.2794)
			(stroke
				(width 0.1)
				(type default)
			)
			(layer "F.Fab")
		)
		(pad "1" smd circle
			(at -0.40005 0 270)
			(size 0 0)
			(layers "F.Cu" "F.Mask" "F.Paste")
			(net "P12V_AUX")
		)
		(pad "2" smd circle
			(at 0.40005 0 270)
			(size 0 0)
			(layers "F.Cu" "F.Mask" "F.Paste")
			(net "GND")
		)
	)
	(footprint ""
		(layer "F.Cu")
		(at 192.828926 -402.67509 -90)
		(property "Reference" "C4493"
			(at 0 0 270)
			(layer "F.SilkS")
			(hide yes)
			(effects
				(font
					(size 1.27 1.27)
				)
			)
		)
		(property "Value" ""
			(at 0 0 270)
			(layer "F.Fab")
			(effects
				(font
					(size 1.27 1.27)
				)
			)
		)
		(duplicate_pad_numbers_are_jumpers no)
		(fp_line
			(start -0.7874 0.4064)
			(end -0.7874 -0.4064)
			(stroke
				(width 0.1524)
				(type default)
			)
			(layer "F.SilkS")
		)
		(fp_line
			(start 0.7874 0.4064)
			(end -0.7874 0.4064)
			(stroke
				(width 0.1524)
				(type default)
			)
			(layer "F.SilkS")
		)
		(fp_line
			(start -0.7874 -0.4064)
			(end 0.7874 -0.4064)
			(stroke
				(width 0.1524)
				(type default)
			)
			(layer "F.SilkS")
		)
		(fp_line
			(start 0.7874 -0.4064)
			(end 0.7874 0.4064)
			(stroke
				(width 0.1524)
				(type default)
			)
			(layer "F.SilkS")
		)
		(fp_line
			(start -0.67945 0.3048)
			(end -0.67945 -0.305054)
			(stroke
				(width 0.1)
				(type default)
			)
			(layer "F.Fab")
		)
		(fp_line
			(start -0.12065 0.3048)
			(end -0.67945 0.3048)
			(stroke
				(width 0.1)
				(type default)
			)
			(layer "F.Fab")
		)
		(fp_line
			(start 0.120396 0.3048)
			(end 0.120396 0.2794)
			(stroke
				(width 0.1)
				(type default)
			)
			(layer "F.Fab")
		)
		(fp_line
			(start 0.67945 0.3048)
			(end 0.120396 0.3048)
			(stroke
				(width 0.1)
				(type default)
			)
			(layer "F.Fab")
		)
		(fp_line
			(start -0.12065 0.2794)
			(end -0.12065 0.3048)
			(stroke
				(width 0.1)
				(type default)
			)
			(layer "F.Fab")
		)
		(fp_line
			(start 0.120396 0.2794)
			(end -0.12065 0.2794)
			(stroke
				(width 0.1)
				(type default)
			)
			(layer "F.Fab")
		)
		(fp_line
			(start -0.12065 -0.2794)
			(end 0.12065 -0.2794)
			(stroke
				(width 0.1)
				(type default)
			)
			(layer "F.Fab")
		)
		(fp_line
			(start 0.12065 -0.2794)
			(end 0.12065 -0.3048)
			(stroke
				(width 0.1)
				(type default)
			)
			(layer "F.Fab")
		)
		(fp_line
			(start 0.12065 -0.3048)
			(end 0.67945 -0.3048)
			(stroke
				(width 0.1)
				(type default)
			)
			(layer "F.Fab")
		)
		(fp_line
			(start 0.67945 -0.3048)
			(end 0.67945 0.3048)
			(stroke
				(width 0.1)
				(type default)
			)
			(layer "F.Fab")
		)
		(fp_line
			(start -0.67945 -0.305054)
			(end -0.12065 -0.305054)
			(stroke
				(width 0.1)
				(type default)
			)
			(layer "F.Fab")
		)
		(fp_line
			(start -0.12065 -0.305054)
			(end -0.12065 -0.2794)
			(stroke
				(width 0.1)
				(type default)
			)
			(layer "F.Fab")
		)
		(pad "1" smd circle
			(at -0.40005 0 270)
			(size 0 0)
			(layers "F.Cu" "F.Mask" "F.Paste")
			(net "FM_UV_LT6700_VS")
		)
		(pad "2" smd circle
			(at 0.40005 0 270)
			(size 0 0)
			(layers "F.Cu" "F.Mask" "F.Paste")
			(net "GND")
		)
	)
	(footprint ""
		(layer "F.Cu")
		(at 270.799814 -152.295352 180)
		(property "Reference" "R221"
			(at 0 0 180)
			(layer "F.SilkS")
			(hide yes)
			(effects
				(font
					(size 1.27 1.27)
				)
			)
		)
		(property "Value" ""
			(at 0 0 180)
			(layer "F.Fab")
			(effects
				(font
					(size 1.27 1.27)
				)
			)
		)
		(duplicate_pad_numbers_are_jumpers no)
		(fp_line
			(start 0.7874 0.4064)
			(end -0.7874 0.4064)
			(stroke
				(width 0.1524)
				(type default)
			)
			(layer "F.SilkS")
		)
		(fp_line
			(start 0.7874 -0.4064)
			(end 0.7874 0.4064)
			(stroke
				(width 0.1524)
				(type default)
			)
			(layer "F.SilkS")
		)
		(fp_line
			(start -0.7874 0.4064)
			(end -0.7874 -0.4064)
			(stroke
				(width 0.1524)
				(type default)
			)
			(layer "F.SilkS")
		)
		(fp_line
			(start -0.7874 -0.4064)
			(end 0.7874 -0.4064)
			(stroke
				(width 0.1524)
				(type default)
			)
			(layer "F.SilkS")
		)
		(fp_line
			(start 0.67945 0.3048)
			(end 0.120396 0.3048)
			(stroke
				(width 0.1)
				(type default)
			)
			(layer "F.Fab")
		)
		(fp_line
			(start 0.67945 -0.3048)
			(end 0.67945 0.3048)
			(stroke
				(width 0.1)
				(type default)
			)
			(layer "F.Fab")
		)
		(fp_line
			(start 0.12065 -0.2794)
			(end 0.12065 -0.3048)
			(stroke
				(width 0.1)
				(type default)
			)
			(layer "F.Fab")
		)
		(fp_line
			(start 0.12065 -0.3048)
			(end 0.67945 -0.3048)
			(stroke
				(width 0.1)
				(type default)
			)
			(layer "F.Fab")
		)
		(fp_line
			(start 0.120396 0.3048)
			(end 0.120396 0.2794)
			(stroke
				(width 0.1)
				(type default)
			)
			(layer "F.Fab")
		)
		(fp_line
			(start 0.120396 0.2794)
			(end -0.12065 0.2794)
			(stroke
				(width 0.1)
				(type default)
			)
			(layer "F.Fab")
		)
		(fp_line
			(start -0.12065 0.3048)
			(end -0.67945 0.3048)
			(stroke
				(width 0.1)
				(type default)
			)
			(layer "F.Fab")
		)
		(fp_line
			(start -0.12065 0.2794)
			(end -0.12065 0.3048)
			(stroke
				(width 0.1)
				(type default)
			)
			(layer "F.Fab")
		)
		(fp_line
			(start -0.12065 -0.2794)
			(end 0.12065 -0.2794)
			(stroke
				(width 0.1)
				(type default)
			)
			(layer "F.Fab")
		)
		(fp_line
			(start -0.12065 -0.305054)
			(end -0.12065 -0.2794)
			(stroke
				(width 0.1)
				(type default)
			)
			(layer "F.Fab")
		)
		(fp_line
			(start -0.67945 0.3048)
			(end -0.67945 -0.305054)
			(stroke
				(width 0.1)
				(type default)
			)
			(layer "F.Fab")
		)
		(fp_line
			(start -0.67945 -0.305054)
			(end -0.12065 -0.305054)
			(stroke
				(width 0.1)
				(type default)
			)
			(layer "F.Fab")
		)
		(pad "1" smd circle
			(at -0.40005 0 180)
			(size 0 0)
			(layers "F.Cu" "F.Mask" "F.Paste")
			(net "NCSI_NIC4_RXD1")
		)
		(pad "2" smd circle
			(at 0.40005 0 180)
			(size 0 0)
			(layers "F.Cu" "F.Mask" "F.Paste")
			(net "GND")
		)
	)
	(footprint ""
		(layer "F.Cu")
		(at 290.264342 -140.6398 180)
		(property "Reference" "R242"
			(at 0 0 180)
			(layer "F.SilkS")
			(hide yes)
			(effects
				(font
					(size 1.27 1.27)
				)
			)
		)
		(property "Value" ""
			(at 0 0 180)
			(layer "F.Fab")
			(effects
				(font
					(size 1.27 1.27)
				)
			)
		)
		(duplicate_pad_numbers_are_jumpers no)
		(fp_line
			(start 0.7874 0.4064)
			(end -0.7874 0.4064)
			(stroke
				(width 0.1524)
				(type default)
			)
			(layer "F.SilkS")
		)
		(fp_line
			(start 0.7874 -0.4064)
			(end 0.7874 0.4064)
			(stroke
				(width 0.1524)
				(type default)
			)
			(layer "F.SilkS")
		)
		(fp_line
			(start -0.7874 0.4064)
			(end -0.7874 -0.4064)
			(stroke
				(width 0.1524)
				(type default)
			)
			(layer "F.SilkS")
		)
		(fp_line
			(start -0.7874 -0.4064)
			(end 0.7874 -0.4064)
			(stroke
				(width 0.1524)
				(type default)
			)
			(layer "F.SilkS")
		)
		(fp_line
			(start 0.67945 0.3048)
			(end 0.120396 0.3048)
			(stroke
				(width 0.1)
				(type default)
			)
			(layer "F.Fab")
		)
		(fp_line
			(start 0.67945 -0.3048)
			(end 0.67945 0.3048)
			(stroke
				(width 0.1)
				(type default)
			)
			(layer "F.Fab")
		)
		(fp_line
			(start 0.12065 -0.2794)
			(end 0.12065 -0.3048)
			(stroke
				(width 0.1)
				(type default)
			)
			(layer "F.Fab")
		)
		(fp_line
			(start 0.12065 -0.3048)
			(end 0.67945 -0.3048)
			(stroke
				(width 0.1)
				(type default)
			)
			(layer "F.Fab")
		)
		(fp_line
			(start 0.120396 0.3048)
			(end 0.120396 0.2794)
			(stroke
				(width 0.1)
				(type default)
			)
			(layer "F.Fab")
		)
		(fp_line
			(start 0.120396 0.2794)
			(end -0.12065 0.2794)
			(stroke
				(width 0.1)
				(type default)
			)
			(layer "F.Fab")
		)
		(fp_line
			(start -0.12065 0.3048)
			(end -0.67945 0.3048)
			(stroke
				(width 0.1)
				(type default)
			)
			(layer "F.Fab")
		)
		(fp_line
			(start -0.12065 0.2794)
			(end -0.12065 0.3048)
			(stroke
				(width 0.1)
				(type default)
			)
			(layer "F.Fab")
		)
		(fp_line
			(start -0.12065 -0.2794)
			(end 0.12065 -0.2794)
			(stroke
				(width 0.1)
				(type default)
			)
			(layer "F.Fab")
		)
		(fp_line
			(start -0.12065 -0.305054)
			(end -0.12065 -0.2794)
			(stroke
				(width 0.1)
				(type default)
			)
			(layer "F.Fab")
		)
		(fp_line
			(start -0.67945 0.3048)
			(end -0.67945 -0.305054)
			(stroke
				(width 0.1)
				(type default)
			)
			(layer "F.Fab")
		)
		(fp_line
			(start -0.67945 -0.305054)
			(end -0.12065 -0.305054)
			(stroke
				(width 0.1)
				(type default)
			)
			(layer "F.Fab")
		)
		(pad "1" smd circle
			(at -0.40005 0 180)
			(size 0 0)
			(layers "F.Cu" "F.Mask" "F.Paste")
			(net "RST_SMB_NIC4_MUX_ISO_N")
		)
		(pad "2" smd circle
			(at 0.40005 0 180)
			(size 0 0)
			(layers "F.Cu" "F.Mask" "F.Paste")
			(net "GND")
		)
	)
	(footprint ""
		(layer "F.Cu")
		(at 184.837832 -356.22103 90)
		(property "Reference" "C2535"
			(at 0 0 90)
			(layer "F.SilkS")
			(hide yes)
			(effects
				(font
					(size 1.27 1.27)
				)
			)
		)
		(property "Value" ""
			(at 0 0 90)
			(layer "F.Fab")
			(effects
				(font
					(size 1.27 1.27)
				)
			)
		)
		(duplicate_pad_numbers_are_jumpers no)
		(fp_line
			(start 0.299974 -0.150114)
			(end 0.299974 0.150114)
			(stroke
				(width 0.1)
				(type default)
			)
			(layer "F.Fab")
		)
		(fp_line
			(start -0.299974 -0.150114)
			(end 0.299974 -0.150114)
			(stroke
				(width 0.1)
				(type default)
			)
			(layer "F.Fab")
		)
		(fp_line
			(start 0.299974 0.150114)
			(end -0.299974 0.150114)
			(stroke
				(width 0.1)
				(type default)
			)
			(layer "F.Fab")
		)
		(fp_line
			(start -0.299974 0.150114)
			(end -0.299974 -0.150114)
			(stroke
				(width 0.1)
				(type default)
			)
			(layer "F.Fab")
		)
		(pad "1" smd rect
			(at -0.2667 0 90)
			(size 0.3048 0.381)
			(layers "F.Cu" "F.Mask" "F.Paste")
			(net "P5E_PEX1_STN4_TX_DN<68>")
		)
		(pad "2" smd rect
			(at 0.2667 0 90)
			(size 0.3048 0.381)
			(layers "F.Cu" "F.Mask" "F.Paste")
			(net "P5E_PEX1_STN4_TX_C_DN<68>")
		)
	)
	(footprint ""
		(layer "F.Cu")
		(at 155.380436 -103.803196)
		(property "Reference" "C271"
			(at 0 0 0)
			(layer "F.SilkS")
			(hide yes)
			(effects
				(font
					(size 1.27 1.27)
				)
			)
		)
		(property "Value" ""
			(at 0 0 0)
			(layer "F.Fab")
			(effects
				(font
					(size 1.27 1.27)
				)
			)
		)
		(duplicate_pad_numbers_are_jumpers no)
		(fp_line
			(start -0.299974 -0.150114)
			(end 0.299974 -0.150114)
			(stroke
				(width 0.1)
				(type default)
			)
			(layer "F.Fab")
		)
		(fp_line
			(start -0.299974 0.150114)
			(end -0.299974 -0.150114)
			(stroke
				(width 0.1)
				(type default)
			)
			(layer "F.Fab")
		)
		(fp_line
			(start 0.299974 -0.150114)
			(end 0.299974 0.150114)
			(stroke
				(width 0.1)
				(type default)
			)
			(layer "F.Fab")
		)
		(fp_line
			(start 0.299974 0.150114)
			(end -0.299974 0.150114)
			(stroke
				(width 0.1)
				(type default)
			)
			(layer "F.Fab")
		)
		(pad "1" smd rect
			(at -0.2667 0)
			(size 0.3048 0.381)
			(layers "F.Cu" "F.Mask" "F.Paste")
			(net "P5E_PEX1_STN1_TX_DN<18>")
		)
		(pad "2" smd rect
			(at 0.2667 0)
			(size 0.3048 0.381)
			(layers "F.Cu" "F.Mask" "F.Paste")
			(net "P5E_PEX1_STN1_TX_C_DN<18>")
		)
	)
)
